(kicad_sch
	(version 20250114)
	(generator "eeschema")
	(generator_version "9.0")
	(paper "A3")
	(title_block
		(title "COM Express 7 Baseboard")
		(date "2025-02-04")
		(rev "1.1.2")
		(company "Antmicro Ltd")
		(comment 1 "www.antmicro.com")
	)
	(text "Backplane connector"
		(exclude_from_sim no)
		(at 185.928 93.472 0)
		(effects
			(font
				(size 2 2)
				(thickness 0.4)
				(bold yes)
			)
			(justify left bottom)
		)
	)
	(text "Vcc is 12V nominal\n"
		(exclude_from_sim no)
		(at 170.18 119.38 0)
		(effects
			(font
				(size 1.27 1.27)
			)
			(justify left bottom)
		)
	)
	(text "PCIe B3x4 can be\nconfigured as 10G-KR\nfor LX2160A"
		(exclude_from_sim no)
		(at 146.05 151.13 0)
		(effects
			(font
				(size 1.27 1.27)
			)
			(justify left bottom)
		)
	)
	(junction
		(at 316.23 175.26)
		(diameter 0)
		(color 0 0 0 0)
	)
	(junction
		(at 274.32 175.26)
		(diameter 0)
		(color 0 0 0 0)
	)
	(junction
		(at 204.47 139.7)
		(diameter 0)
		(color 0 0 0 0)
	)
	(junction
		(at 204.47 172.72)
		(diameter 0)
		(color 0 0 0 0)
	)
	(junction
		(at 190.5 127)
		(diameter 0)
		(color 0 0 0 0)
	)
	(junction
		(at 190.5 157.48)
		(diameter 0)
		(color 0 0 0 0)
	)
	(junction
		(at 204.47 129.54)
		(diameter 0)
		(color 0 0 0 0)
	)
	(junction
		(at 190.5 172.72)
		(diameter 0)
		(color 0 0 0 0)
	)
	(junction
		(at 204.47 124.46)
		(diameter 0)
		(color 0 0 0 0)
	)
	(junction
		(at 190.5 129.54)
		(diameter 0)
		(color 0 0 0 0)
	)
	(junction
		(at 190.5 149.86)
		(diameter 0)
		(color 0 0 0 0)
	)
	(junction
		(at 190.5 132.08)
		(diameter 0)
		(color 0 0 0 0)
	)
	(junction
		(at 274.32 158.75)
		(diameter 0)
		(color 0 0 0 0)
	)
	(junction
		(at 190.5 124.46)
		(diameter 0)
		(color 0 0 0 0)
	)
	(junction
		(at 204.47 127)
		(diameter 0)
		(color 0 0 0 0)
	)
	(junction
		(at 190.5 142.24)
		(diameter 0)
		(color 0 0 0 0)
	)
	(junction
		(at 190.5 165.1)
		(diameter 0)
		(color 0 0 0 0)
	)
	(junction
		(at 204.47 142.24)
		(diameter 0)
		(color 0 0 0 0)
	)
	(junction
		(at 190.5 121.92)
		(diameter 0)
		(color 0 0 0 0)
	)
	(junction
		(at 190.5 120.65)
		(diameter 0)
		(color 0 0 0 0)
	)
	(junction
		(at 190.5 139.7)
		(diameter 0)
		(color 0 0 0 0)
	)
	(junction
		(at 204.47 149.86)
		(diameter 0)
		(color 0 0 0 0)
	)
	(junction
		(at 204.47 132.08)
		(diameter 0)
		(color 0 0 0 0)
	)
	(junction
		(at 204.47 157.48)
		(diameter 0)
		(color 0 0 0 0)
	)
	(no_connect
		(at 275.59 148.59)
	)
	(no_connect
		(at 275.59 132.08)
	)
	(no_connect
		(at 275.59 151.13)
	)
	(bus_entry
		(at 175.26 160.02)
		(size -1.27 1.27)
		(stroke
			(width 0)
			(type default)
		)
	)
	(bus_entry
		(at 175.26 166.37)
		(size 1.27 1.27)
		(stroke
			(width 0)
			(type default)
		)
	)
	(bus_entry
		(at 226.06 148.59)
		(size -1.27 -1.27)
		(stroke
			(width 0)
			(type default)
		)
	)
	(bus_entry
		(at 170.18 153.67)
		(size 1.27 1.27)
		(stroke
			(width 0)
			(type default)
		)
	)
	(bus_entry
		(at 170.18 151.13)
		(size 1.27 1.27)
		(stroke
			(width 0)
			(type default)
		)
	)
	(bus_entry
		(at 226.06 153.67)
		(size -1.27 -1.27)
		(stroke
			(width 0)
			(type default)
		)
	)
	(bus_entry
		(at 226.06 156.21)
		(size -1.27 -1.27)
		(stroke
			(width 0)
			(type default)
		)
	)
	(bus_entry
		(at 175.26 168.91)
		(size 1.27 1.27)
		(stroke
			(width 0)
			(type default)
		)
	)
	(bus_entry
		(at 220.98 166.37)
		(size -1.27 1.27)
		(stroke
			(width 0)
			(type default)
		)
	)
	(bus_entry
		(at 170.18 146.05)
		(size 1.27 1.27)
		(stroke
			(width 0)
			(type default)
		)
	)
	(bus_entry
		(at 226.06 146.05)
		(size -1.27 -1.27)
		(stroke
			(width 0)
			(type default)
		)
	)
	(bus_entry
		(at 170.18 143.51)
		(size 1.27 1.27)
		(stroke
			(width 0)
			(type default)
		)
	)
	(bus_entry
		(at 175.26 162.56)
		(size -1.27 -1.27)
		(stroke
			(width 0)
			(type default)
		)
	)
	(bus_entry
		(at 220.98 168.91)
		(size -1.27 1.27)
		(stroke
			(width 0)
			(type default)
		)
	)
	(wire
		(pts
			(xy 190.5 157.48) (xy 191.77 157.48)
		)
		(stroke
			(width 0)
			(type default)
		)
	)
	(bus
		(pts
			(xy 224.79 179.07) (xy 171.45 179.07)
		)
		(stroke
			(width 0)
			(type default)
		)
	)
	(bus
		(pts
			(xy 226.06 146.05) (xy 226.06 148.59)
		)
		(stroke
			(width 0)
			(type default)
		)
	)
	(wire
		(pts
			(xy 214.63 162.56) (xy 203.2 162.56)
		)
		(stroke
			(width 0)
			(type default)
		)
	)
	(bus
		(pts
			(xy 170.18 140.97) (xy 168.91 139.7)
		)
		(stroke
			(width 0)
			(type default)
		)
	)
	(wire
		(pts
			(xy 203.2 147.32) (xy 224.79 147.32)
		)
		(stroke
			(width 0)
			(type default)
		)
	)
	(wire
		(pts
			(xy 303.53 167.64) (xy 317.5 167.64)
		)
		(stroke
			(width 0)
			(type default)
		)
	)
	(wire
		(pts
			(xy 191.77 139.7) (xy 190.5 139.7)
		)
		(stroke
			(width 0)
			(type default)
		)
	)
	(wire
		(pts
			(xy 274.32 142.24) (xy 275.59 142.24)
		)
		(stroke
			(width 0)
			(type default)
		)
	)
	(wire
		(pts
			(xy 274.32 175.26) (xy 274.32 176.53)
		)
		(stroke
			(width 0)
			(type default)
		)
	)
	(wire
		(pts
			(xy 257.81 172.72) (xy 275.59 172.72)
		)
		(stroke
			(width 0)
			(type default)
		)
	)
	(wire
		(pts
			(xy 204.47 132.08) (xy 203.2 132.08)
		)
		(stroke
			(width 0)
			(type default)
		)
	)
	(wire
		(pts
			(xy 204.47 157.48) (xy 203.2 157.48)
		)
		(stroke
			(width 0)
			(type default)
		)
	)
	(wire
		(pts
			(xy 204.47 124.46) (xy 204.47 127)
		)
		(stroke
			(width 0)
			(type default)
		)
	)
	(wire
		(pts
			(xy 203.2 139.7) (xy 204.47 139.7)
		)
		(stroke
			(width 0)
			(type default)
		)
	)
	(wire
		(pts
			(xy 203.2 170.18) (xy 219.71 170.18)
		)
		(stroke
			(width 0)
			(type default)
		)
	)
	(wire
		(pts
			(xy 204.47 129.54) (xy 203.2 129.54)
		)
		(stroke
			(width 0)
			(type default)
		)
	)
	(wire
		(pts
			(xy 303.53 151.13) (xy 317.5 151.13)
		)
		(stroke
			(width 0)
			(type default)
		)
	)
	(wire
		(pts
			(xy 204.47 149.86) (xy 204.47 157.48)
		)
		(stroke
			(width 0)
			(type default)
		)
	)
	(wire
		(pts
			(xy 257.81 153.67) (xy 275.59 153.67)
		)
		(stroke
			(width 0)
			(type default)
		)
	)
	(wire
		(pts
			(xy 204.47 149.86) (xy 204.47 142.24)
		)
		(stroke
			(width 0)
			(type default)
		)
	)
	(bus
		(pts
			(xy 170.18 143.51) (xy 170.18 146.05)
		)
		(stroke
			(width 0)
			(type default)
		)
	)
	(wire
		(pts
			(xy 190.5 142.24) (xy 190.5 149.86)
		)
		(stroke
			(width 0)
			(type default)
		)
	)
	(wire
		(pts
			(xy 303.53 165.1) (xy 317.5 165.1)
		)
		(stroke
			(width 0)
			(type default)
		)
	)
	(wire
		(pts
			(xy 204.47 129.54) (xy 204.47 132.08)
		)
		(stroke
			(width 0)
			(type default)
		)
	)
	(wire
		(pts
			(xy 191.77 149.86) (xy 190.5 149.86)
		)
		(stroke
			(width 0)
			(type default)
		)
	)
	(bus
		(pts
			(xy 170.18 153.67) (xy 170.18 177.8)
		)
		(stroke
			(width 0)
			(type default)
		)
	)
	(wire
		(pts
			(xy 203.2 172.72) (xy 204.47 172.72)
		)
		(stroke
			(width 0)
			(type default)
		)
	)
	(wire
		(pts
			(xy 190.5 127) (xy 190.5 129.54)
		)
		(stroke
			(width 0)
			(type default)
		)
	)
	(bus
		(pts
			(xy 175.26 166.37) (xy 175.26 168.91)
		)
		(stroke
			(width 0)
			(type default)
		)
	)
	(wire
		(pts
			(xy 190.5 165.1) (xy 190.5 172.72)
		)
		(stroke
			(width 0)
			(type default)
		)
	)
	(bus
		(pts
			(xy 162.56 139.7) (xy 168.91 139.7)
		)
		(stroke
			(width 0)
			(type default)
		)
	)
	(wire
		(pts
			(xy 316.23 175.26) (xy 316.23 176.53)
		)
		(stroke
			(width 0)
			(type default)
		)
	)
	(wire
		(pts
			(xy 257.81 167.64) (xy 275.59 167.64)
		)
		(stroke
			(width 0)
			(type default)
		)
	)
	(wire
		(pts
			(xy 190.5 149.86) (xy 190.5 157.48)
		)
		(stroke
			(width 0)
			(type default)
		)
	)
	(wire
		(pts
			(xy 214.63 160.02) (xy 203.2 160.02)
		)
		(stroke
			(width 0)
			(type default)
		)
	)
	(wire
		(pts
			(xy 203.2 152.4) (xy 224.79 152.4)
		)
		(stroke
			(width 0)
			(type default)
		)
	)
	(wire
		(pts
			(xy 203.2 154.94) (xy 224.79 154.94)
		)
		(stroke
			(width 0)
			(type default)
		)
	)
	(wire
		(pts
			(xy 175.26 160.02) (xy 191.77 160.02)
		)
		(stroke
			(width 0)
			(type default)
		)
	)
	(wire
		(pts
			(xy 203.2 137.16) (xy 204.47 137.16)
		)
		(stroke
			(width 0)
			(type default)
		)
	)
	(bus
		(pts
			(xy 226.06 153.67) (xy 226.06 156.21)
		)
		(stroke
			(width 0)
			(type default)
		)
	)
	(wire
		(pts
			(xy 257.81 156.21) (xy 275.59 156.21)
		)
		(stroke
			(width 0)
			(type default)
		)
	)
	(wire
		(pts
			(xy 203.2 142.24) (xy 204.47 142.24)
		)
		(stroke
			(width 0)
			(type default)
		)
	)
	(bus
		(pts
			(xy 166.37 165.1) (xy 173.99 165.1)
		)
		(stroke
			(width 0)
			(type default)
		)
	)
	(wire
		(pts
			(xy 190.5 132.08) (xy 191.77 132.08)
		)
		(stroke
			(width 0)
			(type default)
		)
	)
	(wire
		(pts
			(xy 316.23 158.75) (xy 317.5 158.75)
		)
		(stroke
			(width 0)
			(type default)
		)
	)
	(bus
		(pts
			(xy 173.99 165.1) (xy 175.26 166.37)
		)
		(stroke
			(width 0)
			(type default)
		)
	)
	(wire
		(pts
			(xy 190.5 129.54) (xy 190.5 132.08)
		)
		(stroke
			(width 0)
			(type default)
		)
	)
	(wire
		(pts
			(xy 203.2 167.64) (xy 219.71 167.64)
		)
		(stroke
			(width 0)
			(type default)
		)
	)
	(wire
		(pts
			(xy 203.2 144.78) (xy 224.79 144.78)
		)
		(stroke
			(width 0)
			(type default)
		)
	)
	(bus
		(pts
			(xy 170.18 146.05) (xy 170.18 151.13)
		)
		(stroke
			(width 0)
			(type default)
		)
	)
	(bus
		(pts
			(xy 222.25 165.1) (xy 220.98 166.37)
		)
		(stroke
			(width 0)
			(type default)
		)
	)
	(wire
		(pts
			(xy 303.53 156.21) (xy 317.5 156.21)
		)
		(stroke
			(width 0)
			(type default)
		)
	)
	(wire
		(pts
			(xy 190.5 120.65) (xy 204.47 120.65)
		)
		(stroke
			(width 0)
			(type default)
		)
	)
	(wire
		(pts
			(xy 204.47 139.7) (xy 204.47 142.24)
		)
		(stroke
			(width 0)
			(type default)
		)
	)
	(wire
		(pts
			(xy 274.32 158.75) (xy 275.59 158.75)
		)
		(stroke
			(width 0)
			(type default)
		)
	)
	(wire
		(pts
			(xy 204.47 127) (xy 204.47 129.54)
		)
		(stroke
			(width 0)
			(type default)
		)
	)
	(bus
		(pts
			(xy 170.18 140.97) (xy 170.18 143.51)
		)
		(stroke
			(width 0)
			(type default)
		)
	)
	(wire
		(pts
			(xy 203.2 149.86) (xy 204.47 149.86)
		)
		(stroke
			(width 0)
			(type default)
		)
	)
	(wire
		(pts
			(xy 203.2 134.62) (xy 204.47 134.62)
		)
		(stroke
			(width 0)
			(type default)
		)
	)
	(wire
		(pts
			(xy 275.59 175.26) (xy 274.32 175.26)
		)
		(stroke
			(width 0)
			(type default)
		)
	)
	(wire
		(pts
			(xy 190.5 142.24) (xy 191.77 142.24)
		)
		(stroke
			(width 0)
			(type default)
		)
	)
	(wire
		(pts
			(xy 171.45 154.94) (xy 191.77 154.94)
		)
		(stroke
			(width 0)
			(type default)
		)
	)
	(wire
		(pts
			(xy 190.5 172.72) (xy 191.77 172.72)
		)
		(stroke
			(width 0)
			(type default)
		)
	)
	(wire
		(pts
			(xy 190.5 139.7) (xy 190.5 142.24)
		)
		(stroke
			(width 0)
			(type default)
		)
	)
	(wire
		(pts
			(xy 274.32 142.24) (xy 274.32 158.75)
		)
		(stroke
			(width 0)
			(type default)
		)
	)
	(wire
		(pts
			(xy 175.26 162.56) (xy 191.77 162.56)
		)
		(stroke
			(width 0)
			(type default)
		)
	)
	(wire
		(pts
			(xy 190.5 165.1) (xy 191.77 165.1)
		)
		(stroke
			(width 0)
			(type default)
		)
	)
	(bus
		(pts
			(xy 220.98 166.37) (xy 220.98 168.91)
		)
		(stroke
			(width 0)
			(type default)
		)
	)
	(wire
		(pts
			(xy 190.5 157.48) (xy 190.5 165.1)
		)
		(stroke
			(width 0)
			(type default)
		)
	)
	(wire
		(pts
			(xy 171.45 147.32) (xy 191.77 147.32)
		)
		(stroke
			(width 0)
			(type default)
		)
	)
	(wire
		(pts
			(xy 257.81 165.1) (xy 275.59 165.1)
		)
		(stroke
			(width 0)
			(type default)
		)
	)
	(wire
		(pts
			(xy 257.81 170.18) (xy 275.59 170.18)
		)
		(stroke
			(width 0)
			(type default)
		)
	)
	(wire
		(pts
			(xy 191.77 137.16) (xy 190.5 137.16)
		)
		(stroke
			(width 0)
			(type default)
		)
	)
	(wire
		(pts
			(xy 257.81 137.16) (xy 275.59 137.16)
		)
		(stroke
			(width 0)
			(type default)
		)
	)
	(wire
		(pts
			(xy 303.53 148.59) (xy 317.5 148.59)
		)
		(stroke
			(width 0)
			(type default)
		)
	)
	(bus
		(pts
			(xy 226.06 177.8) (xy 224.79 179.07)
		)
		(stroke
			(width 0)
			(type default)
		)
	)
	(wire
		(pts
			(xy 190.5 118.11) (xy 190.5 120.65)
		)
		(stroke
			(width 0)
			(type default)
		)
	)
	(wire
		(pts
			(xy 204.47 157.48) (xy 204.47 172.72)
		)
		(stroke
			(width 0)
			(type default)
		)
	)
	(wire
		(pts
			(xy 214.63 165.1) (xy 203.2 165.1)
		)
		(stroke
			(width 0)
			(type default)
		)
	)
	(wire
		(pts
			(xy 191.77 127) (xy 190.5 127)
		)
		(stroke
			(width 0)
			(type default)
		)
	)
	(wire
		(pts
			(xy 316.23 175.26) (xy 317.5 175.26)
		)
		(stroke
			(width 0)
			(type default)
		)
	)
	(wire
		(pts
			(xy 190.5 127) (xy 190.5 124.46)
		)
		(stroke
			(width 0)
			(type default)
		)
	)
	(wire
		(pts
			(xy 190.5 120.65) (xy 190.5 121.92)
		)
		(stroke
			(width 0)
			(type default)
		)
	)
	(wire
		(pts
			(xy 203.2 124.46) (xy 204.47 124.46)
		)
		(stroke
			(width 0)
			(type default)
		)
	)
	(wire
		(pts
			(xy 205.74 187.96) (xy 207.01 187.96)
		)
		(stroke
			(width 0)
			(type default)
		)
	)
	(wire
		(pts
			(xy 205.74 189.23) (xy 205.74 187.96)
		)
		(stroke
			(width 0)
			(type default)
		)
	)
	(wire
		(pts
			(xy 190.5 124.46) (xy 191.77 124.46)
		)
		(stroke
			(width 0)
			(type default)
		)
	)
	(wire
		(pts
			(xy 316.23 175.26) (xy 316.23 158.75)
		)
		(stroke
			(width 0)
			(type default)
		)
	)
	(wire
		(pts
			(xy 190.5 129.54) (xy 191.77 129.54)
		)
		(stroke
			(width 0)
			(type default)
		)
	)
	(wire
		(pts
			(xy 257.81 134.62) (xy 275.59 134.62)
		)
		(stroke
			(width 0)
			(type default)
		)
	)
	(wire
		(pts
			(xy 191.77 134.62) (xy 190.5 134.62)
		)
		(stroke
			(width 0)
			(type default)
		)
	)
	(wire
		(pts
			(xy 274.32 158.75) (xy 274.32 175.26)
		)
		(stroke
			(width 0)
			(type default)
		)
	)
	(wire
		(pts
			(xy 204.47 137.16) (xy 204.47 139.7)
		)
		(stroke
			(width 0)
			(type default)
		)
	)
	(wire
		(pts
			(xy 191.77 170.18) (xy 176.53 170.18)
		)
		(stroke
			(width 0)
			(type default)
		)
	)
	(wire
		(pts
			(xy 203.2 127) (xy 204.47 127)
		)
		(stroke
			(width 0)
			(type default)
		)
	)
	(bus
		(pts
			(xy 170.18 151.13) (xy 170.18 153.67)
		)
		(stroke
			(width 0)
			(type default)
		)
	)
	(bus
		(pts
			(xy 226.06 156.21) (xy 226.06 177.8)
		)
		(stroke
			(width 0)
			(type default)
		)
	)
	(bus
		(pts
			(xy 229.87 165.1) (xy 222.25 165.1)
		)
		(stroke
			(width 0)
			(type default)
		)
	)
	(wire
		(pts
			(xy 171.45 144.78) (xy 191.77 144.78)
		)
		(stroke
			(width 0)
			(type default)
		)
	)
	(wire
		(pts
			(xy 191.77 167.64) (xy 176.53 167.64)
		)
		(stroke
			(width 0)
			(type default)
		)
	)
	(wire
		(pts
			(xy 204.47 172.72) (xy 204.47 180.34)
		)
		(stroke
			(width 0)
			(type default)
		)
	)
	(wire
		(pts
			(xy 204.47 120.65) (xy 204.47 124.46)
		)
		(stroke
			(width 0)
			(type default)
		)
	)
	(wire
		(pts
			(xy 190.5 134.62) (xy 190.5 132.08)
		)
		(stroke
			(width 0)
			(type default)
		)
	)
	(bus
		(pts
			(xy 171.45 179.07) (xy 170.18 177.8)
		)
		(stroke
			(width 0)
			(type default)
		)
	)
	(wire
		(pts
			(xy 303.53 170.18) (xy 317.5 170.18)
		)
		(stroke
			(width 0)
			(type default)
		)
	)
	(wire
		(pts
			(xy 171.45 152.4) (xy 191.77 152.4)
		)
		(stroke
			(width 0)
			(type default)
		)
	)
	(wire
		(pts
			(xy 303.53 153.67) (xy 317.5 153.67)
		)
		(stroke
			(width 0)
			(type default)
		)
	)
	(wire
		(pts
			(xy 257.81 139.7) (xy 275.59 139.7)
		)
		(stroke
			(width 0)
			(type default)
		)
	)
	(bus
		(pts
			(xy 173.99 161.29) (xy 166.37 161.29)
		)
		(stroke
			(width 0)
			(type default)
		)
	)
	(bus
		(pts
			(xy 226.06 148.59) (xy 226.06 153.67)
		)
		(stroke
			(width 0)
			(type default)
		)
	)
	(wire
		(pts
			(xy 190.5 121.92) (xy 190.5 124.46)
		)
		(stroke
			(width 0)
			(type default)
		)
	)
	(wire
		(pts
			(xy 190.5 137.16) (xy 190.5 139.7)
		)
		(stroke
			(width 0)
			(type default)
		)
	)
	(wire
		(pts
			(xy 204.47 134.62) (xy 204.47 132.08)
		)
		(stroke
			(width 0)
			(type default)
		)
	)
	(wire
		(pts
			(xy 190.5 172.72) (xy 190.5 180.34)
		)
		(stroke
			(width 0)
			(type default)
		)
	)
	(wire
		(pts
			(xy 303.53 172.72) (xy 317.5 172.72)
		)
		(stroke
			(width 0)
			(type default)
		)
	)
	(label "UART.RX"
		(at 257.81 153.67 0)
		(effects
			(font
				(size 1.27 1.27)
			)
			(justify left bottom)
		)
	)
	(label "USB.D+"
		(at 179.07 167.64 0)
		(effects
			(font
				(size 1.27 1.27)
			)
			(justify left bottom)
		)
	)
	(label "PCIe_{x2}.TX0+"
		(at 257.81 165.1 0)
		(effects
			(font
				(size 1.27 1.27)
			)
			(justify left bottom)
		)
	)
	(label "PCIe_{x2}.TX1-"
		(at 176.53 154.94 0)
		(effects
			(font
				(size 1.27 1.27)
			)
			(justify left bottom)
		)
	)
	(label "PCIe_{x2}.RX1+"
		(at 223.52 152.4 180)
		(effects
			(font
				(size 1.27 1.27)
			)
			(justify right bottom)
		)
	)
	(label "PCIe_{x2}.RX0-"
		(at 303.53 167.64 0)
		(effects
			(font
				(size 1.27 1.27)
			)
			(justify left bottom)
		)
	)
	(label "USB.D-"
		(at 303.53 156.21 0)
		(effects
			(font
				(size 1.27 1.27)
			)
			(justify left bottom)
		)
	)
	(label "UART.RX"
		(at 205.74 167.64 0)
		(effects
			(font
				(size 1.27 1.27)
			)
			(justify left bottom)
		)
	)
	(label "PCIe_{REF}.CK-"
		(at 187.96 162.56 180)
		(effects
			(font
				(size 1.27 1.27)
			)
			(justify right bottom)
		)
	)
	(label "PCIe_{x2}.RX0+"
		(at 223.52 144.78 180)
		(effects
			(font
				(size 1.27 1.27)
			)
			(justify right bottom)
		)
	)
	(label "PCIe_{REF}.CK+"
		(at 303.53 148.59 0)
		(effects
			(font
				(size 1.27 1.27)
			)
			(justify left bottom)
		)
	)
	(label "PCIe_{REF}.CK+"
		(at 187.96 160.02 180)
		(effects
			(font
				(size 1.27 1.27)
			)
			(justify right bottom)
		)
	)
	(label "~{PRSNT}"
		(at 257.81 137.16 0)
		(effects
			(font
				(size 1.27 1.27)
			)
			(justify left bottom)
		)
	)
	(label "USB.D-"
		(at 179.07 170.18 0)
		(effects
			(font
				(size 1.27 1.27)
			)
			(justify left bottom)
		)
	)
	(label "PCIe_{REF}.CK-"
		(at 303.53 151.13 0)
		(effects
			(font
				(size 1.27 1.27)
			)
			(justify left bottom)
		)
	)
	(label "GPIO"
		(at 257.81 139.7 0)
		(effects
			(font
				(size 1.27 1.27)
			)
			(justify left bottom)
		)
	)
	(label "~{PERST}"
		(at 257.81 134.62 0)
		(effects
			(font
				(size 1.27 1.27)
			)
			(justify left bottom)
		)
	)
	(label "UART.TX"
		(at 205.74 170.18 0)
		(effects
			(font
				(size 1.27 1.27)
			)
			(justify left bottom)
		)
	)
	(label "PCIe_{x2}.RX1-"
		(at 223.52 154.94 180)
		(effects
			(font
				(size 1.27 1.27)
			)
			(justify right bottom)
		)
	)
	(label "UART.TX"
		(at 257.81 156.21 0)
		(effects
			(font
				(size 1.27 1.27)
			)
			(justify left bottom)
		)
	)
	(label "PCIe_{x2}.RX1+"
		(at 303.53 170.18 0)
		(effects
			(font
				(size 1.27 1.27)
			)
			(justify left bottom)
		)
	)
	(label "PCIe_{x2}.TX1-"
		(at 257.81 172.72 0)
		(effects
			(font
				(size 1.27 1.27)
			)
			(justify left bottom)
		)
	)
	(label "PCIe_{x2}.TX1+"
		(at 257.81 170.18 0)
		(effects
			(font
				(size 1.27 1.27)
			)
			(justify left bottom)
		)
	)
	(label "PCIe_{x2}.RX0-"
		(at 223.52 147.32 180)
		(effects
			(font
				(size 1.27 1.27)
			)
			(justify right bottom)
		)
	)
	(label "USB.D+"
		(at 303.53 153.67 0)
		(effects
			(font
				(size 1.27 1.27)
			)
			(justify left bottom)
		)
	)
	(label "PCIe_{x2}.RX0+"
		(at 303.53 165.1 0)
		(effects
			(font
				(size 1.27 1.27)
			)
			(justify left bottom)
		)
	)
	(label "PCIe_{x2}.RX1-"
		(at 303.53 172.72 0)
		(effects
			(font
				(size 1.27 1.27)
			)
			(justify left bottom)
		)
	)
	(label "PCIe_{x2}.TX0-"
		(at 257.81 167.64 0)
		(effects
			(font
				(size 1.27 1.27)
			)
			(justify left bottom)
		)
	)
	(label "PCIe_{x2}.TX1+"
		(at 176.53 152.4 0)
		(effects
			(font
				(size 1.27 1.27)
			)
			(justify left bottom)
		)
	)
	(label "PCIe_{x2}.TX0-"
		(at 176.53 147.32 0)
		(effects
			(font
				(size 1.27 1.27)
			)
			(justify left bottom)
		)
	)
	(label "PCIe_{x2}.TX0+"
		(at 176.53 144.78 0)
		(effects
			(font
				(size 1.27 1.27)
			)
			(justify left bottom)
		)
	)
	(hierarchical_label "~{PRSNT}"
		(shape output)
		(at 214.63 162.56 0)
		(effects
			(font
				(size 1.27 1.27)
			)
			(justify left)
		)
	)
	(hierarchical_label "~{PERST}"
		(shape input)
		(at 214.63 160.02 0)
		(effects
			(font
				(size 1.27 1.27)
			)
			(justify left)
		)
	)
	(hierarchical_label "UART{UART}"
		(shape bidirectional)
		(at 229.87 165.1 0)
		(effects
			(font
				(size 1.27 1.27)
			)
			(justify left)
		)
	)
	(hierarchical_label "PCIe_{REF}{PCIe_{REF}}"
		(shape input)
		(at 166.37 161.29 180)
		(effects
			(font
				(size 1.27 1.27)
			)
			(justify right)
		)
	)
	(hierarchical_label "GPIO"
		(shape bidirectional)
		(at 214.63 165.1 0)
		(effects
			(font
				(size 1.27 1.27)
			)
			(justify left)
		)
	)
	(hierarchical_label "USB{USB}"
		(shape input)
		(at 166.37 165.1 180)
		(effects
			(font
				(size 1.27 1.27)
			)
			(justify right)
		)
	)
	(hierarchical_label "PCIe_{x2}{PCIe}"
		(shape input)
		(at 162.56 139.7 180)
		(effects
			(font
				(size 1.27 1.27)
			)
			(justify right)
		)
	)
	(symbol
		(lib_id "antmicropower:GND")
		(at 190.5 180.34 0)
		(unit 1)
		(exclude_from_sim no)
		(in_bom yes)
		(on_board yes)
		(dnp no)
		(property "Reference" "#PWR081"
			(at 199.39 182.88 0)
			(effects
				(font
					(size 1.27 1.27)
					(thickness 0.15)
				)
				(justify left bottom)
				(hide yes)
			)
		)
		(property "Value" "GND"
			(at 190.5 184.15 0)
			(effects
				(font
					(size 1.27 1.27)
					(thickness 0.15)
				)
			)
		)
		(property "Footprint" ""
			(at 199.39 187.96 0)
			(effects
				(font
					(size 1.27 1.27)
					(thickness 0.15)
				)
				(justify left bottom)
				(hide yes)
			)
		)
		(property "Datasheet" ""
			(at 199.39 193.04 0)
			(effects
				(font
					(size 1.27 1.27)
					(thickness 0.15)
				)
				(justify left bottom)
				(hide yes)
			)
		)
		(property "Description" ""
			(at 190.5 180.34 0)
			(effects
				(font
					(size 1.27 1.27)
				)
				(hide yes)
			)
		)
		(property "Author" "Antmicro"
			(at 199.39 187.96 0)
			(effects
				(font
					(size 1.27 1.27)
					(thickness 0.15)
				)
				(justify left bottom)
				(hide yes)
			)
		)
		(property "License" "Apache-2.0"
			(at 199.39 190.5 0)
			(effects
				(font
					(size 1.27 1.27)
					(thickness 0.15)
				)
				(justify left bottom)
				(hide yes)
			)
		)
		(pin "1"
		)
		(instances
			(project "com-express-7-baseboard"
				(path ""
					(reference "#PWR081")
					(unit 1)
				)
			)
		)
	)
	(symbol
		(lib_id "antmicropower:GND")
		(at 274.32 176.53 0)
		(unit 1)
		(exclude_from_sim no)
		(in_bom yes)
		(on_board yes)
		(dnp no)
		(property "Reference" "#PWR084"
			(at 283.21 179.07 0)
			(effects
				(font
					(size 1.27 1.27)
					(thickness 0.15)
				)
				(justify left bottom)
				(hide yes)
			)
		)
		(property "Value" "GND"
			(at 274.32 180.34 0)
			(effects
				(font
					(size 1.27 1.27)
					(thickness 0.15)
				)
			)
		)
		(property "Footprint" ""
			(at 283.21 184.15 0)
			(effects
				(font
					(size 1.27 1.27)
					(thickness 0.15)
				)
				(justify left bottom)
				(hide yes)
			)
		)
		(property "Datasheet" ""
			(at 283.21 189.23 0)
			(effects
				(font
					(size 1.27 1.27)
					(thickness 0.15)
				)
				(justify left bottom)
				(hide yes)
			)
		)
		(property "Description" ""
			(at 274.32 176.53 0)
			(effects
				(font
					(size 1.27 1.27)
				)
				(hide yes)
			)
		)
		(property "Author" "Antmicro"
			(at 283.21 184.15 0)
			(effects
				(font
					(size 1.27 1.27)
					(thickness 0.15)
				)
				(justify left bottom)
				(hide yes)
			)
		)
		(property "License" "Apache-2.0"
			(at 283.21 186.69 0)
			(effects
				(font
					(size 1.27 1.27)
					(thickness 0.15)
				)
				(justify left bottom)
				(hide yes)
			)
		)
		(pin "1"
		)
		(instances
			(project "com-express-7-baseboard"
				(path ""
					(reference "#PWR084")
					(unit 1)
				)
			)
		)
	)
	(symbol
		(lib_id "antmicropower:PWR_FLAG")
		(at 207.01 187.96 270)
		(unit 1)
		(exclude_from_sim no)
		(in_bom yes)
		(on_board yes)
		(dnp no)
		(fields_autoplaced yes)
		(property "Reference" "#FLG06"
			(at 208.915 187.96 0)
			(effects
				(font
					(size 1.27 1.27)
				)
				(hide yes)
			)
		)
		(property "Value" "PWR_FLAG"
			(at 210.82 187.9599 90)
			(effects
				(font
					(size 1.27 1.27)
				)
				(justify left)
			)
		)
		(property "Footprint" ""
			(at 207.01 187.96 0)
			(effects
				(font
					(size 1.27 1.27)
				)
				(hide yes)
			)
		)
		(property "Datasheet" ""
			(at 207.01 187.96 0)
			(effects
				(font
					(size 1.27 1.27)
				)
				(hide yes)
			)
		)
		(property "Description" ""
			(at 207.01 187.96 0)
			(effects
				(font
					(size 1.27 1.27)
				)
				(hide yes)
			)
		)
		(pin "1"
		)
		(instances
			(project "com-express-7-baseboard"
				(path ""
					(reference "#FLG06")
					(unit 1)
				)
			)
		)
	)
	(symbol
		(lib_id "antmicroTVSDiodes:ESD204DQAR")
		(at 317.5 165.1 0)
		(unit 1)
		(exclude_from_sim no)
		(in_bom yes)
		(on_board yes)
		(dnp no)
		(fields_autoplaced yes)
		(property "Reference" "U16"
			(at 327.66 168.275 0)
			(effects
				(font
					(size 1.27 1.27)
				)
				(justify left)
			)
		)
		(property "Value" "ESD204DQAR"
			(at 328.93 180.34 90)
			(effects
				(font
					(size 1.27 1.27)
					(thickness 0.15)
				)
				(justify left bottom)
				(hide yes)
			)
		)
		(property "Footprint" "antmicro-footprints:USON-10_2.5x1mm_P0.5mm"
			(at 341.63 170.18 0)
			(effects
				(font
					(size 1.27 1.27)
					(thickness 0.15)
				)
				(justify left bottom)
				(hide yes)
			)
		)
		(property "Datasheet" "https://www.ti.com/lit/ds/symlink/esd204.pdf?ts=1706004844383&ref_url=https%253A%252F%252Fwww.ti.com%252Finterface%252Fdiodes%252Fesd-protection-diodes%252Fproducts.html"
			(at 341.63 172.72 0)
			(effects
				(font
					(size 1.27 1.27)
					(thickness 0.15)
				)
				(justify left bottom)
				(hide yes)
			)
		)
		(property "Description" ""
			(at 317.5 165.1 0)
			(effects
				(font
					(size 1.27 1.27)
				)
				(hide yes)
			)
		)
		(property "Manufacturer" "Texas Instruments"
			(at 341.63 175.26 0)
			(effects
				(font
					(size 1.27 1.27)
					(thickness 0.15)
				)
				(justify left bottom)
				(hide yes)
			)
		)
		(property "MPN" "ESD204DQAR"
			(at 327.66 170.815 0)
			(effects
				(font
					(size 1.27 1.27)
					(thickness 0.15)
				)
				(justify left)
			)
		)
		(property "Author" "Antmicro"
			(at 341.63 180.34 0)
			(effects
				(font
					(size 1.27 1.27)
					(thickness 0.15)
				)
				(justify left bottom)
				(hide yes)
			)
		)
		(property "License" "Apache-2.0"
			(at 341.63 182.88 0)
			(effects
				(font
					(size 1.27 1.27)
					(thickness 0.15)
				)
				(justify left bottom)
				(hide yes)
			)
		)
		(pin "1"
		)
		(pin "10"
		)
		(pin "2"
		)
		(pin "3"
		)
		(pin "4"
		)
		(pin "5"
		)
		(pin "6"
		)
		(pin "7"
		)
		(pin "8"
		)
		(pin "9"
		)
		(instances
			(project "com-express-7-baseboard"
				(path ""
					(reference "U16")
					(unit 1)
				)
			)
		)
	)
	(symbol
		(lib_id "antmicropower:GND")
		(at 204.47 180.34 0)
		(unit 1)
		(exclude_from_sim no)
		(in_bom yes)
		(on_board yes)
		(dnp no)
		(property "Reference" "#PWR082"
			(at 213.36 182.88 0)
			(effects
				(font
					(size 1.27 1.27)
					(thickness 0.15)
				)
				(justify left bottom)
				(hide yes)
			)
		)
		(property "Value" "GND"
			(at 204.47 184.15 0)
			(effects
				(font
					(size 1.27 1.27)
					(thickness 0.15)
				)
			)
		)
		(property "Footprint" ""
			(at 213.36 187.96 0)
			(effects
				(font
					(size 1.27 1.27)
					(thickness 0.15)
				)
				(justify left bottom)
				(hide yes)
			)
		)
		(property "Datasheet" ""
			(at 213.36 193.04 0)
			(effects
				(font
					(size 1.27 1.27)
					(thickness 0.15)
				)
				(justify left bottom)
				(hide yes)
			)
		)
		(property "Description" ""
			(at 204.47 180.34 0)
			(effects
				(font
					(size 1.27 1.27)
				)
				(hide yes)
			)
		)
		(property "Author" "Antmicro"
			(at 213.36 187.96 0)
			(effects
				(font
					(size 1.27 1.27)
					(thickness 0.15)
				)
				(justify left bottom)
				(hide yes)
			)
		)
		(property "License" "Apache-2.0"
			(at 213.36 190.5 0)
			(effects
				(font
					(size 1.27 1.27)
					(thickness 0.15)
				)
				(justify left bottom)
				(hide yes)
			)
		)
		(pin "1"
		)
		(instances
			(project "com-express-7-baseboard"
				(path ""
					(reference "#PWR082")
					(unit 1)
				)
			)
		)
	)
	(symbol
		(lib_id "antmicropower:VCC")
		(at 190.5 118.11 0)
		(unit 1)
		(exclude_from_sim no)
		(in_bom yes)
		(on_board yes)
		(dnp no)
		(fields_autoplaced yes)
		(property "Reference" "#PWR080"
			(at 190.5 121.92 0)
			(effects
				(font
					(size 1.27 1.27)
				)
				(hide yes)
			)
		)
		(property "Value" "VCC"
			(at 190.5 113.03 0)
			(effects
				(font
					(size 1.27 1.27)
				)
			)
		)
		(property "Footprint" ""
			(at 190.5 118.11 0)
			(effects
				(font
					(size 1.27 1.27)
				)
				(hide yes)
			)
		)
		(property "Datasheet" ""
			(at 190.5 118.11 0)
			(effects
				(font
					(size 1.27 1.27)
				)
				(hide yes)
			)
		)
		(property "Description" ""
			(at 190.5 118.11 0)
			(effects
				(font
					(size 1.27 1.27)
				)
				(hide yes)
			)
		)
		(pin "1"
		)
		(instances
			(project "com-express-7-baseboard"
				(path ""
					(reference "#PWR080")
					(unit 1)
				)
			)
		)
	)
	(symbol
		(lib_id "antmicroTVSDiodes:ESD204DQAR")
		(at 275.59 148.59 0)
		(unit 1)
		(exclude_from_sim no)
		(in_bom yes)
		(on_board yes)
		(dnp no)
		(fields_autoplaced yes)
		(property "Reference" "U13"
			(at 285.75 151.765 0)
			(effects
				(font
					(size 1.27 1.27)
				)
				(justify left)
			)
		)
		(property "Value" "ESD204DQAR"
			(at 287.02 163.83 90)
			(effects
				(font
					(size 1.27 1.27)
					(thickness 0.15)
				)
				(justify left bottom)
				(hide yes)
			)
		)
		(property "Footprint" "antmicro-footprints:USON-10_2.5x1mm_P0.5mm"
			(at 299.72 153.67 0)
			(effects
				(font
					(size 1.27 1.27)
					(thickness 0.15)
				)
				(justify left bottom)
				(hide yes)
			)
		)
		(property "Datasheet" "https://www.ti.com/lit/ds/symlink/esd204.pdf?ts=1706004844383&ref_url=https%253A%252F%252Fwww.ti.com%252Finterface%252Fdiodes%252Fesd-protection-diodes%252Fproducts.html"
			(at 299.72 156.21 0)
			(effects
				(font
					(size 1.27 1.27)
					(thickness 0.15)
				)
				(justify left bottom)
				(hide yes)
			)
		)
		(property "Description" ""
			(at 275.59 148.59 0)
			(effects
				(font
					(size 1.27 1.27)
				)
				(hide yes)
			)
		)
		(property "Manufacturer" "Texas Instruments"
			(at 299.72 158.75 0)
			(effects
				(font
					(size 1.27 1.27)
					(thickness 0.15)
				)
				(justify left bottom)
				(hide yes)
			)
		)
		(property "MPN" "ESD204DQAR"
			(at 285.75 154.305 0)
			(effects
				(font
					(size 1.27 1.27)
					(thickness 0.15)
				)
				(justify left)
			)
		)
		(property "Author" "Antmicro"
			(at 299.72 163.83 0)
			(effects
				(font
					(size 1.27 1.27)
					(thickness 0.15)
				)
				(justify left bottom)
				(hide yes)
			)
		)
		(property "License" "Apache-2.0"
			(at 299.72 166.37 0)
			(effects
				(font
					(size 1.27 1.27)
					(thickness 0.15)
				)
				(justify left bottom)
				(hide yes)
			)
		)
		(pin "1"
		)
		(pin "10"
		)
		(pin "2"
		)
		(pin "3"
		)
		(pin "4"
		)
		(pin "5"
		)
		(pin "6"
		)
		(pin "7"
		)
		(pin "8"
		)
		(pin "9"
		)
		(instances
			(project "com-express-7-baseboard"
				(path ""
					(reference "U13")
					(unit 1)
				)
			)
		)
	)
	(symbol
		(lib_id "antmicropower:GND")
		(at 316.23 176.53 0)
		(unit 1)
		(exclude_from_sim no)
		(in_bom yes)
		(on_board yes)
		(dnp no)
		(property "Reference" "#PWR085"
			(at 325.12 179.07 0)
			(effects
				(font
					(size 1.27 1.27)
					(thickness 0.15)
				)
				(justify left bottom)
				(hide yes)
			)
		)
		(property "Value" "GND"
			(at 316.23 180.34 0)
			(effects
				(font
					(size 1.27 1.27)
					(thickness 0.15)
				)
			)
		)
		(property "Footprint" ""
			(at 325.12 184.15 0)
			(effects
				(font
					(size 1.27 1.27)
					(thickness 0.15)
				)
				(justify left bottom)
				(hide yes)
			)
		)
		(property "Datasheet" ""
			(at 325.12 189.23 0)
			(effects
				(font
					(size 1.27 1.27)
					(thickness 0.15)
				)
				(justify left bottom)
				(hide yes)
			)
		)
		(property "Description" ""
			(at 316.23 176.53 0)
			(effects
				(font
					(size 1.27 1.27)
				)
				(hide yes)
			)
		)
		(property "Author" "Antmicro"
			(at 325.12 184.15 0)
			(effects
				(font
					(size 1.27 1.27)
					(thickness 0.15)
				)
				(justify left bottom)
				(hide yes)
			)
		)
		(property "License" "Apache-2.0"
			(at 325.12 186.69 0)
			(effects
				(font
					(size 1.27 1.27)
					(thickness 0.15)
				)
				(justify left bottom)
				(hide yes)
			)
		)
		(pin "1"
		)
		(instances
			(project "com-express-7-baseboard"
				(path ""
					(reference "#PWR085")
					(unit 1)
				)
			)
		)
	)
	(symbol
		(lib_id "antmicropower:GND")
		(at 205.74 189.23 0)
		(unit 1)
		(exclude_from_sim no)
		(in_bom yes)
		(on_board yes)
		(dnp no)
		(property "Reference" "#PWR083"
			(at 214.63 191.77 0)
			(effects
				(font
					(size 1.27 1.27)
					(thickness 0.15)
				)
				(justify left bottom)
				(hide yes)
			)
		)
		(property "Value" "GND"
			(at 205.74 193.04 0)
			(effects
				(font
					(size 1.27 1.27)
					(thickness 0.15)
				)
			)
		)
		(property "Footprint" ""
			(at 214.63 196.85 0)
			(effects
				(font
					(size 1.27 1.27)
					(thickness 0.15)
				)
				(justify left bottom)
				(hide yes)
			)
		)
		(property "Datasheet" ""
			(at 214.63 201.93 0)
			(effects
				(font
					(size 1.27 1.27)
					(thickness 0.15)
				)
				(justify left bottom)
				(hide yes)
			)
		)
		(property "Description" ""
			(at 205.74 189.23 0)
			(effects
				(font
					(size 1.27 1.27)
				)
				(hide yes)
			)
		)
		(property "Author" "Antmicro"
			(at 214.63 196.85 0)
			(effects
				(font
					(size 1.27 1.27)
					(thickness 0.15)
				)
				(justify left bottom)
				(hide yes)
			)
		)
		(property "License" "Apache-2.0"
			(at 214.63 199.39 0)
			(effects
				(font
					(size 1.27 1.27)
					(thickness 0.15)
				)
				(justify left bottom)
				(hide yes)
			)
		)
		(pin "1"
		)
		(instances
			(project "com-express-7-baseboard"
				(path ""
					(reference "#PWR083")
					(unit 1)
				)
			)
		)
	)
	(symbol
		(lib_id "antmicropower:PWR_FLAG")
		(at 190.5 121.92 90)
		(unit 1)
		(exclude_from_sim no)
		(in_bom yes)
		(on_board yes)
		(dnp no)
		(fields_autoplaced yes)
		(property "Reference" "#FLG05"
			(at 188.595 121.92 0)
			(effects
				(font
					(size 1.27 1.27)
				)
				(hide yes)
			)
		)
		(property "Value" "PWR_FLAG"
			(at 186.69 121.92 90)
			(effects
				(font
					(size 1.27 1.27)
				)
				(justify left)
			)
		)
		(property "Footprint" ""
			(at 190.5 121.92 0)
			(effects
				(font
					(size 1.27 1.27)
				)
				(hide yes)
			)
		)
		(property "Datasheet" ""
			(at 190.5 121.92 0)
			(effects
				(font
					(size 1.27 1.27)
				)
				(hide yes)
			)
		)
		(property "Description" ""
			(at 190.5 121.92 0)
			(effects
				(font
					(size 1.27 1.27)
				)
				(hide yes)
			)
		)
		(pin "1"
		)
		(instances
			(project "com-express-7-baseboard"
				(path ""
					(reference "#FLG05")
					(unit 1)
				)
			)
		)
	)
	(symbol
		(lib_id "antmicroTVSDiodes:ESD204DQAR")
		(at 275.59 132.08 0)
		(unit 1)
		(exclude_from_sim no)
		(in_bom yes)
		(on_board yes)
		(dnp no)
		(fields_autoplaced yes)
		(property "Reference" "U12"
			(at 285.75 135.255 0)
			(effects
				(font
					(size 1.27 1.27)
				)
				(justify left)
			)
		)
		(property "Value" "ESD204DQAR"
			(at 287.02 147.32 90)
			(effects
				(font
					(size 1.27 1.27)
					(thickness 0.15)
				)
				(justify left bottom)
				(hide yes)
			)
		)
		(property "Footprint" "antmicro-footprints:USON-10_2.5x1mm_P0.5mm"
			(at 299.72 137.16 0)
			(effects
				(font
					(size 1.27 1.27)
					(thickness 0.15)
				)
				(justify left bottom)
				(hide yes)
			)
		)
		(property "Datasheet" "https://www.ti.com/lit/ds/symlink/esd204.pdf?ts=1706004844383&ref_url=https%253A%252F%252Fwww.ti.com%252Finterface%252Fdiodes%252Fesd-protection-diodes%252Fproducts.html"
			(at 299.72 139.7 0)
			(effects
				(font
					(size 1.27 1.27)
					(thickness 0.15)
				)
				(justify left bottom)
				(hide yes)
			)
		)
		(property "Description" ""
			(at 275.59 132.08 0)
			(effects
				(font
					(size 1.27 1.27)
				)
				(hide yes)
			)
		)
		(property "Manufacturer" "Texas Instruments"
			(at 299.72 142.24 0)
			(effects
				(font
					(size 1.27 1.27)
					(thickness 0.15)
				)
				(justify left bottom)
				(hide yes)
			)
		)
		(property "MPN" "ESD204DQAR"
			(at 285.75 137.795 0)
			(effects
				(font
					(size 1.27 1.27)
					(thickness 0.15)
				)
				(justify left)
			)
		)
		(property "Author" "Antmicro"
			(at 299.72 147.32 0)
			(effects
				(font
					(size 1.27 1.27)
					(thickness 0.15)
				)
				(justify left bottom)
				(hide yes)
			)
		)
		(property "License" "Apache-2.0"
			(at 299.72 149.86 0)
			(effects
				(font
					(size 1.27 1.27)
					(thickness 0.15)
				)
				(justify left bottom)
				(hide yes)
			)
		)
		(pin "1"
		)
		(pin "10"
		)
		(pin "2"
		)
		(pin "3"
		)
		(pin "4"
		)
		(pin "5"
		)
		(pin "6"
		)
		(pin "7"
		)
		(pin "8"
		)
		(pin "9"
		)
		(instances
			(project "com-express-7-baseboard"
				(path ""
					(reference "U12")
					(unit 1)
				)
			)
		)
	)
	(symbol
		(lib_id "antmicroEdgeConnectors:PCB-Edge_Samtec_HSEC8_2x20_HSEC8-120-01-S-D-EM2")
		(at 191.77 124.46 0)
		(unit 1)
		(exclude_from_sim no)
		(in_bom no)
		(on_board yes)
		(dnp no)
		(property "Reference" "J16"
			(at 195.58 116.84 0)
			(effects
				(font
					(size 1.27 1.27)
					(thickness 0.15)
				)
			)
		)
		(property "Value" "PCB-Edge_Samtec_HSEC8_2x20_HSEC8-120-01-S-D-EM2"
			(at 222.25 119.38 0)
			(effects
				(font
					(size 1.27 1.27)
					(thickness 0.15)
				)
			)
		)
		(property "Footprint" "antmicro-footprints:PCB-Edge_Samtec_HSEC8_2x20_HSEC8-120-01-S-D-EM2"
			(at 217.17 132.08 0)
			(effects
				(font
					(size 1.27 1.27)
					(thickness 0.15)
				)
				(justify left bottom)
				(hide yes)
			)
		)
		(property "Datasheet" "https://suddendocs.samtec.com/prints/hsec8-1xxx-xx-xx-dv-x-xx-footprint.pdf"
			(at 217.17 134.62 0)
			(effects
				(font
					(size 1.27 1.27)
					(thickness 0.15)
				)
				(justify left bottom)
				(hide yes)
			)
		)
		(property "Description" ""
			(at 191.77 124.46 0)
			(effects
				(font
					(size 1.27 1.27)
				)
				(hide yes)
			)
		)
		(property "Author" "Antmicro"
			(at 217.17 137.16 0)
			(effects
				(font
					(size 1.27 1.27)
					(thickness 0.15)
				)
				(justify left bottom)
				(hide yes)
			)
		)
		(property "License" "Apache-2.0"
			(at 217.17 139.7 0)
			(effects
				(font
					(size 1.27 1.27)
					(thickness 0.15)
				)
				(justify left bottom)
				(hide yes)
			)
		)
		(property "Public" "False"
			(at 217.17 142.24 0)
			(effects
				(font
					(size 1.27 1.27)
				)
				(justify left bottom)
				(hide yes)
			)
		)
		(pin "36"
		)
		(pin "39"
		)
		(pin "17"
		)
		(pin "9"
		)
		(pin "23"
		)
		(pin "24"
		)
		(pin "11"
		)
		(pin "25"
		)
		(pin "20"
		)
		(pin "35"
		)
		(pin "26"
		)
		(pin "3"
		)
		(pin "1"
		)
		(pin "7"
		)
		(pin "2"
		)
		(pin "27"
		)
		(pin "19"
		)
		(pin "21"
		)
		(pin "22"
		)
		(pin "28"
		)
		(pin "31"
		)
		(pin "5"
		)
		(pin "30"
		)
		(pin "38"
		)
		(pin "8"
		)
		(pin "16"
		)
		(pin "12"
		)
		(pin "33"
		)
		(pin "10"
		)
		(pin "32"
		)
		(pin "37"
		)
		(pin "40"
		)
		(pin "13"
		)
		(pin "18"
		)
		(pin "4"
		)
		(pin "29"
		)
		(pin "6"
		)
		(pin "14"
		)
		(pin "15"
		)
		(pin "34"
		)
		(instances
			(project "com-express-7-baseboard"
				(path ""
					(reference "J16")
					(unit 1)
				)
			)
		)
	)
	(symbol
		(lib_id "antmicroTVSDiodes:ESD204DQAR")
		(at 317.5 148.59 0)
		(unit 1)
		(exclude_from_sim no)
		(in_bom yes)
		(on_board yes)
		(dnp no)
		(fields_autoplaced yes)
		(property "Reference" "U15"
			(at 327.66 151.765 0)
			(effects
				(font
					(size 1.27 1.27)
				)
				(justify left)
			)
		)
		(property "Value" "ESD204DQAR"
			(at 328.93 163.83 90)
			(effects
				(font
					(size 1.27 1.27)
					(thickness 0.15)
				)
				(justify left bottom)
				(hide yes)
			)
		)
		(property "Footprint" "antmicro-footprints:USON-10_2.5x1mm_P0.5mm"
			(at 341.63 153.67 0)
			(effects
				(font
					(size 1.27 1.27)
					(thickness 0.15)
				)
				(justify left bottom)
				(hide yes)
			)
		)
		(property "Datasheet" "https://www.ti.com/lit/ds/symlink/esd204.pdf?ts=1706004844383&ref_url=https%253A%252F%252Fwww.ti.com%252Finterface%252Fdiodes%252Fesd-protection-diodes%252Fproducts.html"
			(at 341.63 156.21 0)
			(effects
				(font
					(size 1.27 1.27)
					(thickness 0.15)
				)
				(justify left bottom)
				(hide yes)
			)
		)
		(property "Description" ""
			(at 317.5 148.59 0)
			(effects
				(font
					(size 1.27 1.27)
				)
				(hide yes)
			)
		)
		(property "Manufacturer" "Texas Instruments"
			(at 341.63 158.75 0)
			(effects
				(font
					(size 1.27 1.27)
					(thickness 0.15)
				)
				(justify left bottom)
				(hide yes)
			)
		)
		(property "MPN" "ESD204DQAR"
			(at 327.66 154.305 0)
			(effects
				(font
					(size 1.27 1.27)
					(thickness 0.15)
				)
				(justify left)
			)
		)
		(property "Author" "Antmicro"
			(at 341.63 163.83 0)
			(effects
				(font
					(size 1.27 1.27)
					(thickness 0.15)
				)
				(justify left bottom)
				(hide yes)
			)
		)
		(property "License" "Apache-2.0"
			(at 341.63 166.37 0)
			(effects
				(font
					(size 1.27 1.27)
					(thickness 0.15)
				)
				(justify left bottom)
				(hide yes)
			)
		)
		(pin "1"
		)
		(pin "10"
		)
		(pin "2"
		)
		(pin "3"
		)
		(pin "4"
		)
		(pin "5"
		)
		(pin "6"
		)
		(pin "7"
		)
		(pin "8"
		)
		(pin "9"
		)
		(instances
			(project "com-express-7-baseboard"
				(path ""
					(reference "U15")
					(unit 1)
				)
			)
		)
	)
	(symbol
		(lib_id "antmicroTVSDiodes:ESD204DQAR")
		(at 275.59 165.1 0)
		(unit 1)
		(exclude_from_sim no)
		(in_bom yes)
		(on_board yes)
		(dnp no)
		(fields_autoplaced yes)
		(property "Reference" "U14"
			(at 285.75 168.275 0)
			(effects
				(font
					(size 1.27 1.27)
				)
				(justify left)
			)
		)
		(property "Value" "ESD204DQAR"
			(at 287.02 180.34 90)
			(effects
				(font
					(size 1.27 1.27)
					(thickness 0.15)
				)
				(justify left bottom)
				(hide yes)
			)
		)
		(property "Footprint" "antmicro-footprints:USON-10_2.5x1mm_P0.5mm"
			(at 299.72 170.18 0)
			(effects
				(font
					(size 1.27 1.27)
					(thickness 0.15)
				)
				(justify left bottom)
				(hide yes)
			)
		)
		(property "Datasheet" "https://www.ti.com/lit/ds/symlink/esd204.pdf?ts=1706004844383&ref_url=https%253A%252F%252Fwww.ti.com%252Finterface%252Fdiodes%252Fesd-protection-diodes%252Fproducts.html"
			(at 299.72 172.72 0)
			(effects
				(font
					(size 1.27 1.27)
					(thickness 0.15)
				)
				(justify left bottom)
				(hide yes)
			)
		)
		(property "Description" ""
			(at 275.59 165.1 0)
			(effects
				(font
					(size 1.27 1.27)
				)
				(hide yes)
			)
		)
		(property "Manufacturer" "Texas Instruments"
			(at 299.72 175.26 0)
			(effects
				(font
					(size 1.27 1.27)
					(thickness 0.15)
				)
				(justify left bottom)
				(hide yes)
			)
		)
		(property "MPN" "ESD204DQAR"
			(at 285.75 170.815 0)
			(effects
				(font
					(size 1.27 1.27)
					(thickness 0.15)
				)
				(justify left)
			)
		)
		(property "Author" "Antmicro"
			(at 299.72 180.34 0)
			(effects
				(font
					(size 1.27 1.27)
					(thickness 0.15)
				)
				(justify left bottom)
				(hide yes)
			)
		)
		(property "License" "Apache-2.0"
			(at 299.72 182.88 0)
			(effects
				(font
					(size 1.27 1.27)
					(thickness 0.15)
				)
				(justify left bottom)
				(hide yes)
			)
		)
		(pin "1"
		)
		(pin "10"
		)
		(pin "2"
		)
		(pin "3"
		)
		(pin "4"
		)
		(pin "5"
		)
		(pin "6"
		)
		(pin "7"
		)
		(pin "8"
		)
		(pin "9"
		)
		(instances
			(project "com-express-7-baseboard"
				(path ""
					(reference "U14")
					(unit 1)
				)
			)
		)
	)
)
